# T6G (Grand Teton) — schematic netlist excerpt (pin names and nets, part order shuffled) for the footprints in the layout excerpt that follows; sources: Cadence DE-HDL packaged netlist, KiCad conversion of 04192023_DAF0TMB3IC0_F0TG_MB_C_brd_V02_OCP.brd

R1298  Q_RES  0 5% CHIP  pkg 0402LF  page 159 : A = I3C_SPD_DDRAF_CPU0_SDA ; B = I3C_SPD_DDRAF_CPU0_LVC1_SDA
R1087  Q_RES  0 5% EMPTY  pkg 0402LF  page 312 : A = P1V8_CPU0_RT3_1A_1D ; B = P1V8_CPU0_RT3_1A

(kicad_pcb
	(version 20260206)
	(generator "pcbnew")
	(generator_version "10.0")
	(general
		(thickness 1.6)
		(legacy_teardrops no)
	)
	(paper "A4")
	(title_block
		(title "04192023_DAF0TMB3IC0_F0TG_MB_C_brd_V02_OCP.brd")
		(comment 1 "Grand Teton / footprints 2320-2321 of 8354")
	)
	(layers
		(0 "F.Cu" signal "TOP")
		(4 "In1.Cu" signal "GND")
		(6 "In2.Cu" signal "IN1")
		(8 "In3.Cu" signal "GND1")
		(10 "In4.Cu" signal "IN2")
		(12 "In5.Cu" signal "GND2")
		(14 "In6.Cu" signal "IN3")
		(16 "In7.Cu" signal "GND3")
		(18 "In8.Cu" signal "VCC")
		(20 "In9.Cu" signal "VCC1")
		(22 "In10.Cu" signal "GND4")
		(24 "In11.Cu" signal "IN4")
		(26 "In12.Cu" signal "GND5")
		(28 "In13.Cu" signal "IN5")
		(30 "In14.Cu" signal "GND6")
		(32 "In15.Cu" signal "IN6")
		(34 "In16.Cu" signal "GND7")
		(2 "B.Cu" signal "BOTTOM")
		(9 "F.Adhes" user "F.Adhesive")
		(11 "B.Adhes" user "B.Adhesive")
		(13 "F.Paste" user "Package Geometry/Pastemask Top")
		(15 "B.Paste" user "Package Geometry/Pastemask Bottom")
		(5 "F.SilkS" user "Ref Des/Silkscreen Top")
		(7 "B.SilkS" user "Ref Des/Silkscreen Bottom")
		(1 "F.Mask" user "Board Geometry/Soldermask Top")
		(3 "B.Mask" user "Board Geometry/Soldermask Bottom")
		(17 "Dwgs.User" user "User.Drawings")
		(19 "Cmts.User" user "User.Comments")
		(21 "Eco1.User" user "User.Eco1")
		(23 "Eco2.User" user "User.Eco2")
		(25 "Edge.Cuts" user "Board Geometry/Outline")
		(27 "Margin" user)
		(31 "F.CrtYd" user "Package Geometry/Place Bound Top")
		(29 "B.CrtYd" user "Package Geometry/Place Bound Bottom")
		(35 "F.Fab" user "Ref Des/Assembly Top")
		(33 "B.Fab" user "Ref Des/Assembly Bottom")
	)
	(footprint ""
		(layer "F.Cu")
		(at 296.52595 -150.538942 180)
		(property "Reference" "R1298"
			(at 0 0 180)
			(layer "F.SilkS")
			(hide yes)
			(effects
				(font
					(size 1.27 1.27)
				)
			)
		)
		(property "Value" ""
			(at 0 0 180)
			(layer "F.Fab")
			(effects
				(font
					(size 1.27 1.27)
				)
			)
		)
		(duplicate_pad_numbers_are_jumpers no)
		(fp_line
			(start 0.7874 0.4064)
			(end -0.7874 0.4064)
			(stroke
				(width 0.1524)
				(type default)
			)
			(layer "F.SilkS")
		)
		(fp_line
			(start 0.7874 -0.4064)
			(end 0.7874 0.4064)
			(stroke
				(width 0.1524)
				(type default)
			)
			(layer "F.SilkS")
		)
		(fp_line
			(start -0.7874 0.4064)
			(end -0.7874 -0.4064)
			(stroke
				(width 0.1524)
				(type default)
			)
			(layer "F.SilkS")
		)
		(fp_line
			(start -0.7874 -0.4064)
			(end 0.7874 -0.4064)
			(stroke
				(width 0.1524)
				(type default)
			)
			(layer "F.SilkS")
		)
		(fp_line
			(start 0.67945 0.3048)
			(end 0.120396 0.3048)
			(stroke
				(width 0.1)
				(type default)
			)
			(layer "F.Fab")
		)
		(fp_line
			(start 0.67945 -0.3048)
			(end 0.67945 0.3048)
			(stroke
				(width 0.1)
				(type default)
			)
			(layer "F.Fab")
		)
		(fp_line
			(start 0.12065 -0.2794)
			(end 0.12065 -0.3048)
			(stroke
				(width 0.1)
				(type default)
			)
			(layer "F.Fab")
		)
		(fp_line
			(start 0.12065 -0.3048)
			(end 0.67945 -0.3048)
			(stroke
				(width 0.1)
				(type default)
			)
			(layer "F.Fab")
		)
		(fp_line
			(start 0.120396 0.3048)
			(end 0.120396 0.2794)
			(stroke
				(width 0.1)
				(type default)
			)
			(layer "F.Fab")
		)
		(fp_line
			(start 0.120396 0.2794)
			(end -0.12065 0.2794)
			(stroke
				(width 0.1)
				(type default)
			)
			(layer "F.Fab")
		)
		(fp_line
			(start -0.12065 0.3048)
			(end -0.67945 0.3048)
			(stroke
				(width 0.1)
				(type default)
			)
			(layer "F.Fab")
		)
		(fp_line
			(start -0.12065 0.2794)
			(end -0.12065 0.3048)
			(stroke
				(width 0.1)
				(type default)
			)
			(layer "F.Fab")
		)
		(fp_line
			(start -0.12065 -0.2794)
			(end 0.12065 -0.2794)
			(stroke
				(width 0.1)
				(type default)
			)
			(layer "F.Fab")
		)
		(fp_line
			(start -0.12065 -0.305054)
			(end -0.12065 -0.2794)
			(stroke
				(width 0.1)
				(type default)
			)
			(layer "F.Fab")
		)
		(fp_line
			(start -0.67945 0.3048)
			(end -0.67945 -0.305054)
			(stroke
				(width 0.1)
				(type default)
			)
			(layer "F.Fab")
		)
		(fp_line
			(start -0.67945 -0.305054)
			(end -0.12065 -0.305054)
			(stroke
				(width 0.1)
				(type default)
			)
			(layer "F.Fab")
		)
		(pad "1" smd rect
			(at -0.40005 0)
			(size 0.4572 0.508)
			(layers "F.Cu" "F.Mask" "F.Paste")
			(net "I3C_SPD_DDRAF_CPU0_SDA")
		)
		(pad "2" smd rect
			(at 0.40005 0)
			(size 0.4572 0.508)
			(layers "F.Cu" "F.Mask" "F.Paste")
			(net "I3C_SPD_DDRAF_CPU0_LVC1_SDA")
		)
	)
	(footprint ""
		(layer "F.Cu")
		(at 392.962384 -393.47648 180)
		(property "Reference" "R1087"
			(at 0 0 180)
			(layer "F.SilkS")
			(hide yes)
			(effects
				(font
					(size 1.27 1.27)
				)
			)
		)
		(property "Value" ""
			(at 0 0 180)
			(layer "F.Fab")
			(effects
				(font
					(size 1.27 1.27)
				)
			)
		)
		(duplicate_pad_numbers_are_jumpers no)
		(fp_line
			(start 0.7874 0.4064)
			(end -0.7874 0.4064)
			(stroke
				(width 0.1524)
				(type default)
			)
			(layer "F.SilkS")
		)
		(fp_line
			(start 0.7874 -0.4064)
			(end 0.7874 0.4064)
			(stroke
				(width 0.1524)
				(type default)
			)
			(layer "F.SilkS")
		)
		(fp_line
			(start -0.7874 0.4064)
			(end -0.7874 -0.4064)
			(stroke
				(width 0.1524)
				(type default)
			)
			(layer "F.SilkS")
		)
		(fp_line
			(start -0.7874 -0.4064)
			(end 0.7874 -0.4064)
			(stroke
				(width 0.1524)
				(type default)
			)
			(layer "F.SilkS")
		)
		(fp_line
			(start 0.67945 0.3048)
			(end 0.120396 0.3048)
			(stroke
				(width 0.1)
				(type default)
			)
			(layer "F.Fab")
		)
		(fp_line
			(start 0.67945 -0.3048)
			(end 0.67945 0.3048)
			(stroke
				(width 0.1)
				(type default)
			)
			(layer "F.Fab")
		)
		(fp_line
			(start 0.12065 -0.2794)
			(end 0.12065 -0.3048)
			(stroke
				(width 0.1)
				(type default)
			)
			(layer "F.Fab")
		)
		(fp_line
			(start 0.12065 -0.3048)
			(end 0.67945 -0.3048)
			(stroke
				(width 0.1)
				(type default)
			)
			(layer "F.Fab")
		)
		(fp_line
			(start 0.120396 0.3048)
			(end 0.120396 0.2794)
			(stroke
				(width 0.1)
				(type default)
			)
			(layer "F.Fab")
		)
		(fp_line
			(start 0.120396 0.2794)
			(end -0.12065 0.2794)
			(stroke
				(width 0.1)
				(type default)
			)
			(layer "F.Fab")
		)
		(fp_line
			(start -0.12065 0.3048)
			(end -0.67945 0.3048)
			(stroke
				(width 0.1)
				(type default)
			)
			(layer "F.Fab")
		)
		(fp_line
			(start -0.12065 0.2794)
			(end -0.12065 0.3048)
			(stroke
				(width 0.1)
				(type default)
			)
			(layer "F.Fab")
		)
		(fp_line
			(start -0.12065 -0.2794)
			(end 0.12065 -0.2794)
			(stroke
				(width 0.1)
				(type default)
			)
			(layer "F.Fab")
		)
		(fp_line
			(start -0.12065 -0.305054)
			(end -0.12065 -0.2794)
			(stroke
				(width 0.1)
				(type default)
			)
			(layer "F.Fab")
		)
		(fp_line
			(start -0.67945 0.3048)
			(end -0.67945 -0.305054)
			(stroke
				(width 0.1)
				(type default)
			)
			(layer "F.Fab")
		)
		(fp_line
			(start -0.67945 -0.305054)
			(end -0.12065 -0.305054)
			(stroke
				(width 0.1)
				(type default)
			)
			(layer "F.Fab")
		)
		(pad "1" smd rect
			(at -0.40005 0)
			(size 0.4572 0.508)
			(layers "F.Cu" "F.Mask" "F.Paste")
			(net "P1V8_CPU0_RT3_1A_1D")
		)
		(pad "2" smd rect
			(at 0.40005 0)
			(size 0.4572 0.508)
			(layers "F.Cu" "F.Mask" "F.Paste")
			(net "P1V8_CPU0_RT3_1A")
		)
	)
)
